# BASEBOARD_FAB2 (Tioga Pass) — schematic netlist excerpt (pin names and nets, part order shuffled) for the footprints in the layout excerpt that follows; sources: Cadence DE-HDL packaged netlist, KiCad conversion of Wiwynn_Tioga_Pass_MB.brd

R7G29  RES  1.00K 1% CHIP  pkg 0402  page 136 : A = PD_PASSWORD_CLEAR ; B = GND
R2U37  RES  0.0 5% CHIP  pkg 0402  page 108 : A = RST_PCIE_RISER1_PERST_N ; B = RST_PCIE_RISER1_PERST_R_N
R4P8  RES  90.9 1% CHIP  pkg 0402  page 21 : A = A_CPU0_ABC_RCOMP0 ; B = GND

(kicad_pcb
	(version 20260206)
	(generator "pcbnew")
	(generator_version "10.0")
	(general
		(thickness 1.6)
		(legacy_teardrops no)
	)
	(paper "A4")
	(title_block
		(title "Wiwynn_Tioga_Pass_MB.brd")
		(comment 1 "Tioga Pass / footprints 3483-3485 of 4770")
	)
	(layers
		(0 "F.Cu" signal "TOP")
		(4 "In1.Cu" signal "L2GND")
		(6 "In2.Cu" signal "L3")
		(8 "In3.Cu" signal "L4GND")
		(10 "In4.Cu" signal "L5")
		(12 "In5.Cu" signal "L6GND")
		(14 "In6.Cu" signal "L7VCC")
		(16 "In7.Cu" signal "L8VCC")
		(18 "In8.Cu" signal "L9GND")
		(20 "In9.Cu" signal "L10")
		(22 "In10.Cu" signal "L11GND")
		(24 "In11.Cu" signal "L12")
		(26 "In12.Cu" signal "L13GND")
		(2 "B.Cu" signal "BOTTOM")
		(9 "F.Adhes" user "F.Adhesive")
		(11 "B.Adhes" user "B.Adhesive")
		(13 "F.Paste" user "Package Geometry/Pastemask Top")
		(15 "B.Paste" user "Package Geometry/Pastemask Bottom")
		(5 "F.SilkS" user "Ref Des/Silkscreen Top")
		(7 "B.SilkS" user "Ref Des/Silkscreen Bottom")
		(1 "F.Mask" user "Board Geometry/Soldermask Top")
		(3 "B.Mask" user "Board Geometry/Soldermask Bottom")
		(17 "Dwgs.User" user "User.Drawings")
		(19 "Cmts.User" user "User.Comments")
		(21 "Eco1.User" user "User.Eco1")
		(23 "Eco2.User" user "User.Eco2")
		(25 "Edge.Cuts" user "Board Geometry/Outline")
		(27 "Margin" user)
		(31 "F.CrtYd" user "Package Geometry/Place Bound Top")
		(29 "B.CrtYd" user "Package Geometry/Place Bound Bottom")
		(35 "F.Fab" user "Ref Des/Assembly Top")
		(33 "B.Fab" user "Ref Des/Assembly Bottom")
	)
	(footprint ""
		(layer "B.Cu")
		(at 367.9444 -5.3467 180)
		(property "Reference" "R7G29"
			(at 0 0 0)
			(layer "B.SilkS")
			(hide yes)
			(effects
				(font
					(size 1.27 1.27)
				)
				(justify mirror)
			)
		)
		(property "Value" ""
			(at 0 0 0)
			(layer "B.Fab")
			(effects
				(font
					(size 1.27 1.27)
				)
				(justify mirror)
			)
		)
		(duplicate_pad_numbers_are_jumpers no)
		(fp_poly
			(pts
				(xy 0.2794 -0.1016) (xy -0.2794 -0.1016) (xy -0.2794 0.9906) (xy 0.2794 0.9906)
			)
			(stroke
				(width 0)
				(type default)
			)
			(fill no)
			(layer "B.CrtYd")
		)
		(fp_line
			(start 0.2794 0.9906)
			(end -0.2794 0.9906)
			(stroke
				(width 0.1)
				(type default)
			)
			(layer "B.Fab")
		)
		(fp_line
			(start 0.2794 -0.1016)
			(end 0.2794 0.9906)
			(stroke
				(width 0.1)
				(type default)
			)
			(layer "B.Fab")
		)
		(fp_line
			(start -0.2794 0.9906)
			(end -0.2794 -0.1016)
			(stroke
				(width 0.1)
				(type default)
			)
			(layer "B.Fab")
		)
		(fp_line
			(start -0.2794 -0.1016)
			(end 0.2794 -0.1016)
			(stroke
				(width 0.1)
				(type default)
			)
			(layer "B.Fab")
		)
		(pad "1" smd rect
			(at 0 0)
			(size 0.508 0.508)
			(layers "B.Cu" "B.Mask" "B.Paste")
			(net "PD_PASSWORD_CLEAR")
		)
		(pad "2" smd rect
			(at 0 0.889)
			(size 0.508 0.508)
			(layers "B.Cu" "B.Mask" "B.Paste")
			(net "GND")
		)
		(zone
			(layer "B.Cu")
			(hatch none 0.5)
			(connect_pads
				(clearance 0)
			)
			(min_thickness 0.25)
			(keepout
				(tracks not_allowed)
				(vias allowed)
				(pads allowed)
				(copperpour not_allowed)
				(footprints allowed)
			)
			(placement
				(enabled no)
				(sheetname "")
			)
			(fill
				(thermal_gap 0.5)
				(thermal_bridge_width 0.5)
				(island_removal_mode 0)
			)
			(polygon
				(pts
					(xy 367.6904 -5.9817) (xy 368.1984 -5.9817) (xy 368.1984 -5.6007) (xy 367.6904 -5.6007)
				)
			)
		)
		(zone
			(layer "B.Cu")
			(hatch none 0.5)
			(connect_pads
				(clearance 0)
			)
			(min_thickness 0.25)
			(keepout
				(tracks allowed)
				(vias not_allowed)
				(pads allowed)
				(copperpour not_allowed)
				(footprints allowed)
			)
			(placement
				(enabled no)
				(sheetname "")
			)
			(fill
				(thermal_gap 0.5)
				(thermal_bridge_width 0.5)
				(island_removal_mode 0)
			)
			(polygon
				(pts
					(xy 367.6904 -5.6007) (xy 368.1984 -5.6007) (xy 368.1984 -5.9817) (xy 367.6904 -5.9817)
				)
			)
		)
	)
	(footprint ""
		(layer "B.Cu")
		(at 462.8896 -7.1628)
		(property "Reference" "R2U37"
			(at 0 0 0)
			(layer "B.SilkS")
			(hide yes)
			(effects
				(font
					(size 1.27 1.27)
				)
				(justify mirror)
			)
		)
		(property "Value" ""
			(at 0 0 0)
			(layer "B.Fab")
			(effects
				(font
					(size 1.27 1.27)
				)
				(justify mirror)
			)
		)
		(duplicate_pad_numbers_are_jumpers no)
		(fp_poly
			(pts
				(xy 0.2794 -0.1016) (xy -0.2794 -0.1016) (xy -0.2794 0.9906) (xy 0.2794 0.9906)
			)
			(stroke
				(width 0)
				(type default)
			)
			(fill no)
			(layer "B.CrtYd")
		)
		(fp_line
			(start -0.2794 -0.1016)
			(end 0.2794 -0.1016)
			(stroke
				(width 0.1)
				(type default)
			)
			(layer "B.Fab")
		)
		(fp_line
			(start -0.2794 0.9906)
			(end -0.2794 -0.1016)
			(stroke
				(width 0.1)
				(type default)
			)
			(layer "B.Fab")
		)
		(fp_line
			(start 0.2794 -0.1016)
			(end 0.2794 0.9906)
			(stroke
				(width 0.1)
				(type default)
			)
			(layer "B.Fab")
		)
		(fp_line
			(start 0.2794 0.9906)
			(end -0.2794 0.9906)
			(stroke
				(width 0.1)
				(type default)
			)
			(layer "B.Fab")
		)
		(pad "1" smd rect
			(at 0 0 180)
			(size 0.508 0.508)
			(layers "B.Cu" "B.Mask" "B.Paste")
			(net "RST_PCIE_RISER1_PERST_N")
		)
		(pad "2" smd rect
			(at 0 0.889 180)
			(size 0.508 0.508)
			(layers "B.Cu" "B.Mask" "B.Paste")
			(net "RST_PCIE_RISER1_PERST_R_N")
		)
		(zone
			(layer "B.Cu")
			(hatch none 0.5)
			(connect_pads
				(clearance 0)
			)
			(min_thickness 0.25)
			(keepout
				(tracks allowed)
				(vias not_allowed)
				(pads allowed)
				(copperpour not_allowed)
				(footprints allowed)
			)
			(placement
				(enabled no)
				(sheetname "")
			)
			(fill
				(thermal_gap 0.5)
				(thermal_bridge_width 0.5)
				(island_removal_mode 0)
			)
			(polygon
				(pts
					(xy 463.1436 -6.9088) (xy 462.6356 -6.9088) (xy 462.6356 -6.5278) (xy 463.1436 -6.5278)
				)
			)
		)
		(zone
			(layer "B.Cu")
			(hatch none 0.5)
			(connect_pads
				(clearance 0)
			)
			(min_thickness 0.25)
			(keepout
				(tracks not_allowed)
				(vias allowed)
				(pads allowed)
				(copperpour not_allowed)
				(footprints allowed)
			)
			(placement
				(enabled no)
				(sheetname "")
			)
			(fill
				(thermal_gap 0.5)
				(thermal_bridge_width 0.5)
				(island_removal_mode 0)
			)
			(polygon
				(pts
					(xy 463.1436 -6.5278) (xy 462.6356 -6.5278) (xy 462.6356 -6.9088) (xy 463.1436 -6.9088)
				)
			)
		)
	)
	(footprint ""
		(layer "B.Cu")
		(at 282.259024 -73.492614 -90)
		(property "Reference" "R4P8"
			(at 0 0 90)
			(layer "B.SilkS")
			(hide yes)
			(effects
				(font
					(size 1.27 1.27)
				)
				(justify mirror)
			)
		)
		(property "Value" ""
			(at 0 0 90)
			(layer "B.Fab")
			(effects
				(font
					(size 1.27 1.27)
				)
				(justify mirror)
			)
		)
		(duplicate_pad_numbers_are_jumpers no)
		(fp_rect
			(start 0.2794 0.9906)
			(end -0.2794 -0.1016)
			(stroke
				(width 0)
				(type default)
			)
			(fill no)
			(layer "B.CrtYd")
		)
		(fp_line
			(start -0.2794 0.9906)
			(end -0.2794 -0.1016)
			(stroke
				(width 0.1)
				(type default)
			)
			(layer "B.Fab")
		)
		(fp_line
			(start 0.2794 0.9906)
			(end -0.2794 0.9906)
			(stroke
				(width 0.1)
				(type default)
			)
			(layer "B.Fab")
		)
		(fp_line
			(start -0.2794 -0.1016)
			(end 0.2794 -0.1016)
			(stroke
				(width 0.1)
				(type default)
			)
			(layer "B.Fab")
		)
		(fp_line
			(start 0.2794 -0.1016)
			(end 0.2794 0.9906)
			(stroke
				(width 0.1)
				(type default)
			)
			(layer "B.Fab")
		)
		(pad "1" smd rect
			(at 0 0 90)
			(size 0.508 0.508)
			(layers "B.Cu" "B.Mask" "B.Paste")
			(net "A_CPU0_ABC_RCOMP0")
		)
		(pad "2" smd rect
			(at 0 0.889 90)
			(size 0.508 0.508)
			(layers "B.Cu" "B.Mask" "B.Paste")
			(net "GND")
		)
		(zone
			(layer "B.Cu")
			(hatch none 0.5)
			(connect_pads
				(clearance 0)
			)
			(min_thickness 0.25)
			(keepout
				(tracks allowed)
				(vias not_allowed)
				(pads allowed)
				(copperpour not_allowed)
				(footprints allowed)
			)
			(placement
				(enabled no)
				(sheetname "")
			)
			(fill
				(thermal_gap 0.5)
				(thermal_bridge_width 0.5)
				(island_removal_mode 0)
			)
			(polygon
				(pts
					(xy 281.624024 -73.238614) (xy 282.005024 -73.238614) (xy 282.005024 -73.746614) (xy 281.624024 -73.746614)
				)
			)
		)
		(zone
			(layer "B.Cu")
			(hatch none 0.5)
			(connect_pads
				(clearance 0)
			)
			(min_thickness 0.25)
			(keepout
				(tracks not_allowed)
				(vias allowed)
				(pads allowed)
				(copperpour not_allowed)
				(footprints allowed)
			)
			(placement
				(enabled no)
				(sheetname "")
			)
			(fill
				(thermal_gap 0.5)
				(thermal_bridge_width 0.5)
				(island_removal_mode 0)
			)
			(polygon
				(pts
					(xy 281.624024 -73.238614) (xy 282.005024 -73.238614) (xy 282.005024 -73.746614) (xy 281.624024 -73.746614)
				)
			)
		)
	)
)
